# T6G (Grand Teton) — schematic netlist excerpt (pin names and nets, part order shuffled) for the footprints in the layout excerpt that follows; sources: Cadence DE-HDL packaged netlist, KiCad conversion of 04192023_DAF0TMB3IC0_F0TG_MB_C_brd_V02_OCP.brd

R6301  Q_RES  10K 1% CHIP  pkg 0402LF  page 178 : A = P3V3_AUX ; B = USB_HUB2_TI_OVERCUR3
R1129  Q_RES  0 5% CHIP  pkg 0402LF  page 136 : A = HP_LVC3_OCP_V3_1_P12V_PWRGD ; B = HP_LVC3_OCP_V3_1_P12V_R_PWRGD

(kicad_pcb
	(version 20260206)
	(generator "pcbnew")
	(generator_version "10.0")
	(general
		(thickness 1.6)
		(legacy_teardrops no)
	)
	(paper "A4")
	(title_block
		(title "04192023_DAF0TMB3IC0_F0TG_MB_C_brd_V02_OCP.brd")
		(comment 1 "Grand Teton / footprints 4562-4563 of 8354")
	)
	(layers
		(0 "F.Cu" signal "TOP")
		(4 "In1.Cu" signal "GND")
		(6 "In2.Cu" signal "IN1")
		(8 "In3.Cu" signal "GND1")
		(10 "In4.Cu" signal "IN2")
		(12 "In5.Cu" signal "GND2")
		(14 "In6.Cu" signal "IN3")
		(16 "In7.Cu" signal "GND3")
		(18 "In8.Cu" signal "VCC")
		(20 "In9.Cu" signal "VCC1")
		(22 "In10.Cu" signal "GND4")
		(24 "In11.Cu" signal "IN4")
		(26 "In12.Cu" signal "GND5")
		(28 "In13.Cu" signal "IN5")
		(30 "In14.Cu" signal "GND6")
		(32 "In15.Cu" signal "IN6")
		(34 "In16.Cu" signal "GND7")
		(2 "B.Cu" signal "BOTTOM")
		(9 "F.Adhes" user "F.Adhesive")
		(11 "B.Adhes" user "B.Adhesive")
		(13 "F.Paste" user "Package Geometry/Pastemask Top")
		(15 "B.Paste" user "Package Geometry/Pastemask Bottom")
		(5 "F.SilkS" user "Ref Des/Silkscreen Top")
		(7 "B.SilkS" user "Ref Des/Silkscreen Bottom")
		(1 "F.Mask" user "Board Geometry/Soldermask Top")
		(3 "B.Mask" user "Board Geometry/Soldermask Bottom")
		(17 "Dwgs.User" user "User.Drawings")
		(19 "Cmts.User" user "User.Comments")
		(21 "Eco1.User" user "User.Eco1")
		(23 "Eco2.User" user "User.Eco2")
		(25 "Edge.Cuts" user "Board Geometry/Outline")
		(27 "Margin" user)
		(31 "F.CrtYd" user "Package Geometry/Place Bound Top")
		(29 "B.CrtYd" user "Package Geometry/Place Bound Bottom")
		(35 "F.Fab" user "Ref Des/Assembly Top")
		(33 "B.Fab" user "Ref Des/Assembly Bottom")
	)
	(footprint ""
		(layer "F.Cu")
		(at 112.597946 -54.882034 -90)
		(property "Reference" "R6301"
			(at 0 0 270)
			(layer "F.SilkS")
			(hide yes)
			(effects
				(font
					(size 1.27 1.27)
				)
			)
		)
		(property "Value" ""
			(at 0 0 270)
			(layer "F.Fab")
			(effects
				(font
					(size 1.27 1.27)
				)
			)
		)
		(duplicate_pad_numbers_are_jumpers no)
		(fp_line
			(start -0.7874 0.4064)
			(end -0.7874 -0.4064)
			(stroke
				(width 0.1524)
				(type default)
			)
			(layer "F.SilkS")
		)
		(fp_line
			(start 0.7874 0.4064)
			(end -0.7874 0.4064)
			(stroke
				(width 0.1524)
				(type default)
			)
			(layer "F.SilkS")
		)
		(fp_line
			(start -0.7874 -0.4064)
			(end 0.7874 -0.4064)
			(stroke
				(width 0.1524)
				(type default)
			)
			(layer "F.SilkS")
		)
		(fp_line
			(start 0.7874 -0.4064)
			(end 0.7874 0.4064)
			(stroke
				(width 0.1524)
				(type default)
			)
			(layer "F.SilkS")
		)
		(fp_line
			(start -0.67945 0.3048)
			(end -0.67945 -0.305054)
			(stroke
				(width 0.1)
				(type default)
			)
			(layer "F.Fab")
		)
		(fp_line
			(start -0.12065 0.3048)
			(end -0.67945 0.3048)
			(stroke
				(width 0.1)
				(type default)
			)
			(layer "F.Fab")
		)
		(fp_line
			(start 0.120396 0.3048)
			(end 0.120396 0.2794)
			(stroke
				(width 0.1)
				(type default)
			)
			(layer "F.Fab")
		)
		(fp_line
			(start 0.67945 0.3048)
			(end 0.120396 0.3048)
			(stroke
				(width 0.1)
				(type default)
			)
			(layer "F.Fab")
		)
		(fp_line
			(start -0.12065 0.2794)
			(end -0.12065 0.3048)
			(stroke
				(width 0.1)
				(type default)
			)
			(layer "F.Fab")
		)
		(fp_line
			(start 0.120396 0.2794)
			(end -0.12065 0.2794)
			(stroke
				(width 0.1)
				(type default)
			)
			(layer "F.Fab")
		)
		(fp_line
			(start -0.12065 -0.2794)
			(end 0.12065 -0.2794)
			(stroke
				(width 0.1)
				(type default)
			)
			(layer "F.Fab")
		)
		(fp_line
			(start 0.12065 -0.2794)
			(end 0.12065 -0.3048)
			(stroke
				(width 0.1)
				(type default)
			)
			(layer "F.Fab")
		)
		(fp_line
			(start 0.12065 -0.3048)
			(end 0.67945 -0.3048)
			(stroke
				(width 0.1)
				(type default)
			)
			(layer "F.Fab")
		)
		(fp_line
			(start 0.67945 -0.3048)
			(end 0.67945 0.3048)
			(stroke
				(width 0.1)
				(type default)
			)
			(layer "F.Fab")
		)
		(fp_line
			(start -0.67945 -0.305054)
			(end -0.12065 -0.305054)
			(stroke
				(width 0.1)
				(type default)
			)
			(layer "F.Fab")
		)
		(fp_line
			(start -0.12065 -0.305054)
			(end -0.12065 -0.2794)
			(stroke
				(width 0.1)
				(type default)
			)
			(layer "F.Fab")
		)
		(pad "1" smd circle
			(at -0.40005 0 270)
			(size 0 0)
			(layers "F.Cu" "F.Mask" "F.Paste")
			(net "P3V3_AUX")
		)
		(pad "2" smd circle
			(at 0.40005 0 270)
			(size 0 0)
			(layers "F.Cu" "F.Mask" "F.Paste")
			(net "USB_HUB2_TI_OVERCUR3")
		)
	)
	(footprint ""
		(layer "F.Cu")
		(at 198.489824 -96.422718 90)
		(property "Reference" "R1129"
			(at 0 0 90)
			(layer "F.SilkS")
			(hide yes)
			(effects
				(font
					(size 1.27 1.27)
				)
			)
		)
		(property "Value" ""
			(at 0 0 90)
			(layer "F.Fab")
			(effects
				(font
					(size 1.27 1.27)
				)
			)
		)
		(duplicate_pad_numbers_are_jumpers no)
		(fp_line
			(start 0.7874 -0.4064)
			(end 0.7874 0.4064)
			(stroke
				(width 0.1524)
				(type default)
			)
			(layer "F.SilkS")
		)
		(fp_line
			(start -0.7874 -0.4064)
			(end 0.7874 -0.4064)
			(stroke
				(width 0.1524)
				(type default)
			)
			(layer "F.SilkS")
		)
		(fp_line
			(start 0.7874 0.4064)
			(end -0.7874 0.4064)
			(stroke
				(width 0.1524)
				(type default)
			)
			(layer "F.SilkS")
		)
		(fp_line
			(start -0.7874 0.4064)
			(end -0.7874 -0.4064)
			(stroke
				(width 0.1524)
				(type default)
			)
			(layer "F.SilkS")
		)
		(fp_line
			(start -0.12065 -0.305054)
			(end -0.12065 -0.2794)
			(stroke
				(width 0.1)
				(type default)
			)
			(layer "F.Fab")
		)
		(fp_line
			(start -0.67945 -0.305054)
			(end -0.12065 -0.305054)
			(stroke
				(width 0.1)
				(type default)
			)
			(layer "F.Fab")
		)
		(fp_line
			(start 0.67945 -0.3048)
			(end 0.67945 0.3048)
			(stroke
				(width 0.1)
				(type default)
			)
			(layer "F.Fab")
		)
		(fp_line
			(start 0.12065 -0.3048)
			(end 0.67945 -0.3048)
			(stroke
				(width 0.1)
				(type default)
			)
			(layer "F.Fab")
		)
		(fp_line
			(start 0.12065 -0.2794)
			(end 0.12065 -0.3048)
			(stroke
				(width 0.1)
				(type default)
			)
			(layer "F.Fab")
		)
		(fp_line
			(start -0.12065 -0.2794)
			(end 0.12065 -0.2794)
			(stroke
				(width 0.1)
				(type default)
			)
			(layer "F.Fab")
		)
		(fp_line
			(start 0.120396 0.2794)
			(end -0.12065 0.2794)
			(stroke
				(width 0.1)
				(type default)
			)
			(layer "F.Fab")
		)
		(fp_line
			(start -0.12065 0.2794)
			(end -0.12065 0.3048)
			(stroke
				(width 0.1)
				(type default)
			)
			(layer "F.Fab")
		)
		(fp_line
			(start 0.67945 0.3048)
			(end 0.120396 0.3048)
			(stroke
				(width 0.1)
				(type default)
			)
			(layer "F.Fab")
		)
		(fp_line
			(start 0.120396 0.3048)
			(end 0.120396 0.2794)
			(stroke
				(width 0.1)
				(type default)
			)
			(layer "F.Fab")
		)
		(fp_line
			(start -0.12065 0.3048)
			(end -0.67945 0.3048)
			(stroke
				(width 0.1)
				(type default)
			)
			(layer "F.Fab")
		)
		(fp_line
			(start -0.67945 0.3048)
			(end -0.67945 -0.305054)
			(stroke
				(width 0.1)
				(type default)
			)
			(layer "F.Fab")
		)
		(pad "1" smd circle
			(at -0.40005 0 90)
			(size 0 0)
			(layers "F.Cu" "F.Mask" "F.Paste")
			(net "HP_LVC3_OCP_V3_1_P12V_PWRGD")
		)
		(pad "2" smd circle
			(at 0.40005 0 90)
			(size 0 0)
			(layers "F.Cu" "F.Mask" "F.Paste")
			(net "HP_LVC3_OCP_V3_1_P12V_R_PWRGD")
		)
	)
)
